FILE_TYPE = CONNECTIVITY;
{Allegro Design Entry HDL 17.2-2016 S081 (4005846) 1/11/2022}
"PAGE_NUMBER" = 54;
0"NC";
1"GND\g";
2"PVDD18_S5_P1\g";
3"GND\g";
4"GND\g";
5"GND\g";
6"GND\g";
7"GND\g";
8"GND\g";
9"GND\g";
10"GND\g";
11"FM_P1_PCC0_N";
12"SVID_PVDDCR_CPU1_P1_SVTO";
13"CPU1_THERMTRIP_N";
14"CPU1_BP2";
15"APML_CPU1_ALERT_N";
16"CPU1_BP1";
17"CPU1_BP0";
18"PVDD18_S5_P1\g";
19"CPU1_XTRIG_L7";
20"CPU1_PROCHOT_N";
21"CPU1_XTRIG_L6";
22"CPU1_XTRIG_L4";
23"CPU1_XTRIG_L5";
24"JTAG_CPU1_TDO";
25"P3V3_STBY\g";
26"PVDD18_S5_P1\g";
27"CPU1_SA0";
28"CPU1_SA1";
29"CPU1_SP5R1";
30"CPU1_SP5R2";
31"CPU1_SP5R3";
32"CPU1_SP5R4";
33"CPU1_CORETYPE0";
34"CPU1_CORETYPE1";
35"CPU1_CORETYPE2";
36"JTAG_CPU1_TCK";
37"JTAG_CPU1_TDI";
38"JTAG_CPU1_TRST_N";
39"JTAG_CPU1_DBREQ_N";
40"JTAG_CPU1_TMS";
41"TP_CPU1_TEST50_IOD";
42"VSENSE_VSS_SENSE_A_P1";
43"VSENSE_VSS_SENSE_B_P1";
44"VSENSE_VSS_SENSE_C_P1";
45"VSENSE_PVDD18_S5_P1_DN";
46"VSENSE_PVDDIO_P1_DP";
47"VSENSE_PVDD11_S3_P1_DP";
48"VSENSE_PVDD18_S5_P1_DP";
49"TP_VSENSE_PVDD33_S5_P1";
50"VSENSE_PVDDCR_SOC_P1_DP";
51"VSENSE_PVDDCR_CPU1_P1_DP";
52"VSENSE_PVDDCR_CPU0_P1_DP";
53"TP_CPU1_TEST47_CCD0";
54"TP_CPU1_TEST47_CCD1";
55"TP_CPU1_TEST47_CCD2";
56"TP_CPU1_TEST47_IOD0";
57"TP_CPU1_TEST47_IOD1";
58"TP_CPU1_TEST47_CCD3";
59"PRSNT_CPU1_N";
60"CPU1_SA0";
61"CPU1_SA1";
62"CPU1_SP5R1";
63"CPU1_SP5R2";
64"CPU1_SP5R4";
65"CPU1_SP5R3";
66"CPU1_CORETYPE0";
67"CPU1_CORETYPE1";
68"CPU1_CORETYPE2";
69"SVID_PVDDCR_CPU0_P1_SVD_R";
70"SVID_PVDDCR_CPU0_P1_SVC_R";
71"SVID_PVDDCR_CPU1_P1_SVD_R";
72"SVID_PVDDCR_CPU1_P1_SVC_R";
73"JTAG_CPU1_TDO";
74"SVID_PVDDCR_CPU0_P1_SVD";
75"SVID_PVDDCR_CPU1_P1_SVD";
76"SVID_PVDDCR_CPU0_P1_SVC";
77"SVID_PVDDCR_CPU1_P1_SVC";
78"FM_P1_PCC1_N";
79"SVID_PVDDCR_CPU0_P1_SVTO";
80"JTAG_CPU1_TDI";
81"JTAG_CPU1_TRST_N";
82"JTAG_CPU1_TCK";
83"JTAG_CPU1_TMS";
84"JTAG_CPU1_DBREQ_N";
85"JTAG_CPU1_R_TDO";
86"SMB_APML_CPU1_SDA";
87"SMB_APML_CPU1_SCL";
88"TP_CPU1_UART0_INTR";
89"TP_CPU1_TEST5_IOD";
90"TP_CPU1_TEST41_IOD";
91"TP_CPU1_UART0_RX";
92"TP_CPU1_UART0_RTS_N";
93"TP_CPU1_UART0_TX";
94"TP_CPU1_UART0_CTS_N";
95"TP_CPU1_UART1_RX";
96"TP_CPU1_TEST5_CCD0";
97"TP_CPU1_TEST5_CCD1";
98"TP_CPU1_TEST5_CCD2";
99"TP_CPU1_TEST5_CCD3";
100"TP_CPU1_TEST4_IOD";
101"TP_CPU1_TEST5_CCD4";
102"TP_CPU1_TEST5_CCD5";
103"TP_CPU1_TEST5_CCD6";
104"TP_CPU1_TEST5_CCD7";
105"TP_CPU1_TEST5_CCD8";
106"TP_CPU1_TEST4_CCD7";
107"TP_CPU1_TEST5_CCD9";
108"TP_CPU1_TEST4_CCD8";
109"TP_CPU1_TEST4_CCD10";
110"TP_CPU1_TEST4_CCD9";
111"TP_CPU1_TEST5_CCD10";
112"TP_CPU1_TEST4_CCD11";
113"TP_CPU1_TEST5_CCD11";
114"TP_CPU1_TEST6_X3D4";
115"TP_CPU1_TEST6_CCD1";
116"TP_CPU1_TEST6_X3D5";
117"TP_CPU1_TEST6_CCD2";
118"TP_CPU1_TEST4_CCD0";
119"TP_CPU1_TEST6_CCD3";
120"TP_CPU1_TEST4_CCD1";
121"TP_CPU1_TEST4_CCD2";
122"TP_CPU1_TEST4_CCD3";
123"TP_CPU1_TEST6_IOD";
124"TP_CPU1_TEST4_CCD4";
125"TP_CPU1_TEST4_CCD5";
126"TP_CPU1_TEST4_CCD6";
127"TP_CPU1_TEST6_X3D0";
128"TP_CPU1_TEST6_X3D1";
129"TP_CPU1_TEST6_X3D2";
130"TP_CPU1_TEST6_X3D3";
131"CPU1_BP3";
132"CPU1_BP2";
133"CPU1_BP0";
134"CPU1_BP1";
135"CPU1_XTRIG_L4";
136"CPU1_XTRIG_L5";
137"CPU1_XTRIG_L6";
138"CPU1_XTRIG_L7";
139"CPU1_XTRIG_R1_L5";
140"CPU1_XTRIG_R1_L4";
141"CPU1_XTRIG_R1_L7";
142"CPU1_XTRIG_R1_L6";
143"GND\g";
144"GND\g";
145"CPU1_THERMTRIP_N";
146"CPU1_XTRIG_R2_L4";
147"CPU1_XTRIG_R2_L5";
148"CPU1_XTRIG_R2_L6";
149"CPU1_XTRIG_R2_L7";
150"TP_CPU1_TEST6_CCD0";
151"CPU1_BP1";
152"CPU1_BP0";
153"CPU1_BP2";
154"CPU1_BP3";
155"APML_CPU1_ALERT_N";
156"NC_CPU1_AZ_BITCLK";
157"NC_CPU1_AZ_SDIN2";
158"NC_CPU1_AZ_SDOUT";
159"NC_CPU1_AZ_SDIN1";
160"NC_CPU1_AZ_RST_N";
161"NC_CPU1_AZ_SDIN0";
162"NC_CPU1_AZ_SYNC";
163"CPU1_PROCHOT_N";
164"CPU1_XTRIG_L5";
165"CPU1_XTRIG_L6";
166"CPU1_XTRIG_L4";
167"CPU1_XTRIG_L7";
168"CPU1_THERMTRIP_R_N";
169"APML_CPU1_ALERT_R_N";
170"CPU1_BP3";
%"UNIVERSAL_POWER"
"1","(-150,6225)","0","pure_quanta_power","I156";
;
HDL_POWER"PVDD18_S5_P1"
CDS_LIB"pure_quanta_power";
"A"18;
%"SCONN8_G802M0083150RD3EU"
"1","(-500,3575)","0","pure_quanta","I184";
;
LOCATION"J7"
$SEC"1"
CDS_SEC"1"
PART_TYPE"SMLF"
MATERIAL"IO"
VALUE"SCONN8_G802M0083150RD3EU"
PART_NUMBER"DFHD08MS351"
CDS_LIB"pure_quanta"
NEEDS_NO_SIZE"TRUE"
CDS_LMAN_SYM_OUTLINE"-125,125,125,-125";
"8"
$PN"8"144;
"7"
$PN"7"141;
"6"
$PN"6"144;
"5"
$PN"5"142;
"4"
$PN"4"144;
"3"
$PN"3"139;
"2"
$PN"2"144;
"1"
$PN"1"140;
%"GENOA_SP5"
"20","(-4650,3750)","0","pure_quanta","I190";
;
LOCATION"U26"
$SEC"20"
CDS_SEC"20"
MATERIAL"IO"
VALUE"SOCKET6096_13568-001"
PART_TYPE"SMLF"
PART_NUMBER"DGA^6000030"
CDS_LIB"pure_quanta"
CDS_LMAN_SYM_OUTLINE"-600,2425,600,-2425"
NEEDS_NO_SIZE"TRUE";
"CORETYPE2"
$PN"D68"68;
"BP3"
$PN"A62"154;
"BP2"
$PN"A63"153;
"BP1"
$PN"C62"151;
"BP0"
$PN"C63"152;
"TEST41_IOD"
$PN"W31"90;
"TEST47_CCD3"
$PN"E32"58;
"TEST6_CCD0"
$PN"AA46"150;
"TEST6_X3D3"
$PN"CJ52"130;
"TEST6_X3D2"
$PN"AA29"129;
"TEST47_IOD1"
$PN"D7"57;
"TEST6_X3D1"
$PN"CJ29"128;
"TEST47_IOD0"
$PN"B58"56;
"TEST6_X3D0"
$PN"AA47"127;
"TEST5_CCD11"
$PN"Y29"113;
"TEST4_CCD11"
$PN"AA28"112;
"TEST5_CCD10"
$PN"CK47"111;
"TEST4_CCD9"
$PN"CK30"110;
"TEST4_CCD10"
$PN"CJ47"109;
"TEST47_CCD2"
$PN"CK46"55;
"TEST4_CCD8"
$PN"AA48"108;
"TEST5_CCD9"
$PN"CK29"107;
"TEST47_CCD1"
$PN"CJ24"54;
"TEST4_CCD7"
$PN"AA27"106;
"TEST50_IOD"
$PN"B61"41;
"TEST5_CCD8"
$PN"Y47"105;
"TEST47_CCD0"
$PN"B60"53;
"TEST4_CCD6"
$PN"CJ50"126;
"TEST5_CCD7"
$PN"AA26"104;
"TEST4_CCD5"
$PN"CJ26"125;
"TEST5_CCD6"
$PN"CJ51"103;
"TEST4_CCD4"
$PN"AA52"124;
"TEST5_CCD5"
$PN"CJ25"102;
"TEST6_IOD"
$PN"AA49"123;
"TEST4_CCD3"
$PN"AA30"122;
"TEST5_CCD4"
$PN"AA53"101;
"TEST5_IOD"
$PN"AA24"89;
"TEST4_CCD2"
$PN"CJ48"121;
"TEST4_IOD"
$PN"AA25"100;
"TEST5_CCD3"
$PN"Y30"99;
"TEST4_CCD1"
$PN"CJ28"120;
"TEST5_CCD2"
$PN"CJ49"98;
"TEST6_CCD3"
$PN"Y46"119;
"TEST4_CCD0"
$PN"AA50"118;
"TEST5_CCD1"
$PN"CJ27"97;
"TEST6_CCD2"
$PN"CJ46"117;
"TEST6_X3D5"
$PN"CJ53"116;
"TEST5_CCD0"
$PN"AA51"96;
"TEST6_CCD1"
$PN"CJ30"115;
"TEST6_X3D4"
$PN"AA23"114;
"VDDCR_CPU0_SENSE"
$PN"C2"52;
"VDDCR_CPU1_SENSE"
$PN"DG3"51;
"VDDCR_SOC_SENSE"
$PN"B3"50;
"VDD_33_S5_SENSE"
$PN"BP53"49;
"VDD_18_S5_SENSE"
$PN"C74"48;
"VDD_11_S3_SENSE"
$PN"DH3"47;
"VDDIO_SENSE"
$PN"BR53"46;
"VSS_SENSE_D"
$PN"B73"45;
"VSS_SENSE_C"
$PN"DJ3"44;
"VSS_SENSE_B"
$PN"BR54"43;
"VSS_SENSE_A"
$PN"C3"42;
"UART1_TXD||AGPIO142"
$PN"DJ32"0;
"UART1_RXD||AGPIO141"
$PN"DH33"95;
"RTC_LDO_SELECT"
$PN"DH8"1;
"TCK"
$PN"B17"82;
"SP5R1"
$PN"C19"62;
"AZ_SDIN1||SW_MCLK"
$PN"D33"159;
"AZ_SDIN0||SW_MDATA3"
$PN"C33"161;
"AZ_RST_L||SW_MDATA1"
$PN"A34"160;
"AZ_SDOUT||SW_MDATA2"
$PN"A32"158;
"AZ_SDIN2||SW_MDATA0"
$PN"A33"157;
"UART0_CTS_L||UART2_TXD||AGPIO135"
$PN"DJ33"94;
"UART0_TXD||AGPIO138"
$PN"DJ34"93;
"UART0_INTR||AGPIO139"
$PN"DG34"88;
"UART0_RTS_L||UART2_RXD||AGPIO137"
$PN"DF34"92;
"UART0_RXD||AGPIO136"
$PN"DG35"91;
"SVC1"
$PN"DJ72"77;
"SVT1"
$PN"DG73"12;
"SVC0"
$PN"A23"76;
"SVD1"
$PN"DH72"75;
"SVT0"
$PN"B21"79;
"SVD0"
$PN"A22"74;
"AZ_SYNC"
$PN"D32"162;
"AZ_BITCLK"
$PN"C32"156;
"PCC1_L \B"
$PN"DG72"78;
"PCC0_L \B"
$PN"C22"11;
"SP5R4"
$PN"DH10"64;
"SP5R3"
$PN"DH73"65;
"SP5R2"
$PN"C68"63;
"CORETYPE1"
$PN"B69"67;
"CORETYPE0"
$PN"C70"66;
"SA1"
$PN"DJ56"61;
"XTRIG_L7 \B"
$PN"A65"149;
"XTRIG_L6 \B"
$PN"A66"148;
"XTRIG_L5 \B"
$PN"C65"147;
"XTRIG_L4 \B"
$PN"C66"146;
"TRST_L \B"
$PN"A17"81;
"TMS"
$PN"A16"83;
"THERMTRIP_L \B"
$PN"DJ9"145;
"TDO"
$PN"C18"85;
"TDI"
$PN"C17"80;
"SID"
$PN"DH71"86;
"SIC"
$PN"DJ71"87;
"SA0"
$PN"DJ55"60;
"PROCHOT_L \B"
$PN"A69"163;
"DBREQ_L \B"
$PN"C16"84;
"CPU_PRESENT_L"
$PN"B66"59;
"ALERT_L \B"
$PN"A68"155;
%"Q_RES"
"1","(-6100,4825)","2","pure_quanta","I203";
;
LOCATION"R529"
$SEC"1"
CDS_SEC"1"
VALUE"0"
CDS_LIB"pure_quanta"
WATTAGE"1/16W"
MATERIAL"CHIP"
TOLERANCE"5%"
PART_NUMBER"CS00002JB38"
PACK_TYPE"0402LF";
"B"
$PN"2"73;
"A"
$PN"1"85;
%"TP"
"1","(-6150,1900)","6","pure_quanta","I237";
;
LOCATION"TP20"
$SEC"1"
CDS_SEC"1"
MATERIAL"NA"
CDS_LIB"pure_quanta"
PART_NUMBER"TP30"
PACK_TYPE"TP";
"TP \B"
$PN"1"
$PIN_NUMBER"?"50;
%"TP"
"1","(-6225,1900)","6","pure_quanta","I238";
;
LOCATION"TP19"
$SEC"1"
CDS_SEC"1"
MATERIAL"NA"
CDS_LIB"pure_quanta"
PART_NUMBER"TP30"
PACK_TYPE"TP";
"TP \B"
$PN"1"
$PIN_NUMBER"?"48;
%"UNIVERSAL_GND"
"1","(-5650,1225)","0","pure_quanta_power","I239";
;
CDS_LIB"pure_quanta_power"
HDL_POWER"GND";
"A"1;
%"TP"
"1","(-6325,1900)","6","pure_quanta","I240";
;
LOCATION"TP18"
$SEC"1"
CDS_SEC"1"
MATERIAL"NA"
CDS_LIB"pure_quanta"
PART_NUMBER"TP30"
PACK_TYPE"TP";
"TP \B"
$PN"1"
$PIN_NUMBER"?"47;
%"TP"
"1","(-6400,1900)","6","pure_quanta","I241";
;
LOCATION"TP17"
$SEC"1"
CDS_SEC"1"
MATERIAL"NA"
CDS_LIB"pure_quanta"
PART_NUMBER"TP30"
PACK_TYPE"TP";
"TP \B"
$PN"1"
$PIN_NUMBER"?"52;
%"TP"
"1","(-6475,1900)","6","pure_quanta","I242";
;
LOCATION"TP16"
$SEC"1"
CDS_SEC"1"
MATERIAL"NA"
CDS_LIB"pure_quanta"
PART_NUMBER"TP30"
PACK_TYPE"TP";
"TP \B"
$PN"1"
$PIN_NUMBER"?"51;
%"TP"
"1","(-6550,1900)","6","pure_quanta","I243";
;
LOCATION"TP15"
$SEC"1"
CDS_SEC"1"
MATERIAL"NA"
CDS_LIB"pure_quanta"
PART_NUMBER"TP30"
PACK_TYPE"TP";
"TP \B"
$PN"1"
$PIN_NUMBER"?"46;
%"TP"
"1","(-6675,1900)","6","pure_quanta","I244";
;
LOCATION"TP14"
$SEC"1"
CDS_SEC"1"
MATERIAL"NA"
CDS_LIB"pure_quanta"
PART_NUMBER"TP30"
PACK_TYPE"TP";
"TP \B"
$PN"1"
$PIN_NUMBER"?"45;
%"TP"
"1","(-6750,1900)","6","pure_quanta","I245";
;
LOCATION"TP13"
$SEC"1"
CDS_SEC"1"
MATERIAL"NA"
CDS_LIB"pure_quanta"
PART_NUMBER"TP30"
PACK_TYPE"TP";
"TP \B"
$PN"1"
$PIN_NUMBER"?"44;
%"TP"
"1","(-6825,1900)","6","pure_quanta","I272";
;
LOCATION"TP12"
$SEC"1"
CDS_SEC"1"
MATERIAL"NA"
CDS_LIB"pure_quanta"
PART_NUMBER"TP30"
PACK_TYPE"TP";
"TP \B"
$PN"1"
$PIN_NUMBER"?"43;
%"TP"
"1","(-6900,1900)","6","pure_quanta","I273";
;
LOCATION"TP11"
$SEC"1"
CDS_SEC"1"
MATERIAL"NA"
CDS_LIB"pure_quanta"
PART_NUMBER"TP30"
PACK_TYPE"TP";
"TP \B"
$PN"1"
$PIN_NUMBER"?"42;
%"UNIVERSAL_POWER"
"1","(-8750,5000)","0","pure_quanta_power","I286";
;
HDL_POWER"PVDD18_S5_P1"
CDS_LIB"pure_quanta_power";
"A"2;
%"GND"
"1","(-8625,4275)","0","pure_quanta_power","I289";
;
SIZE"1B"
CDS_LIB"pure_quanta_power"
HDL_POWER"GND";
"A<SIZE-1..0>\NAC"3;
%"GND"
"1","(-8750,4275)","0","pure_quanta_power","I291";
;
SIZE"1B"
CDS_LIB"pure_quanta_power"
HDL_POWER"GND";
"A<SIZE-1..0>\NAC"4;
%"SCONN8_G802M0083150RD3EU"
"1","(-1025,2525)","0","pure_quanta","I302";
;
LOCATION"J49"
$SEC"1"
CDS_SEC"1"
PART_TYPE"SMLF"
MATERIAL"IO"
VALUE"SCONN8_G802M0083150RD3EU"
PART_NUMBER"DFHD08MS351"
CDS_LIB"pure_quanta"
NEEDS_NO_SIZE"TRUE"
CDS_LMAN_SYM_OUTLINE"-125,125,125,-125";
"8"
$PN"8"143;
"7"
$PN"7"131;
"6"
$PN"6"143;
"5"
$PN"5"132;
"4"
$PN"4"143;
"3"
$PN"3"134;
"2"
$PN"2"143;
"1"
$PN"1"133;
%"Q_RES"
"2","(-6725,1325)","0","pure_quanta","I308";
;
LOCATION"R528"
$SEC"1"
CDS_SEC"1"
WATTAGE"1/16W"
MATERIAL"CHIP"
TOLERANCE"5%"
VALUE"1K"
PART_NUMBER"TMP_QCS21002JB34"
PACK_TYPE"0402LF"
CDS_LIB"pure_quanta";
"A"
$PN"1"26;
"B"
$PN"2"39;
%"Q_RES"
"2","(-7000,1325)","0","pure_quanta","I309";
;
LOCATION"R527"
$SEC"1"
CDS_SEC"1"
WATTAGE"1/16W"
MATERIAL"CHIP"
TOLERANCE"5%"
VALUE"1K"
PACK_TYPE"0402LF"
CDS_LIB"pure_quanta"
PART_NUMBER"TMP_QCS21002JB34";
"A"
$PN"1"26;
"B"
$PN"2"40;
%"Q_CAP"
"1","(-6725,625)","0","pure_quanta","I310";
;
LOCATION"C235"
$SEC"1"
CDS_SEC"1"
MATERIAL"EMPTY"
TOLERANCE"10%"
VALUE"0.001UF"
PART_NUMBER"CH30106KB19"
VOLTAGE"50V"
PACK_TYPE"C0402"
CDS_LIB"pure_quanta";
"B"
$PN"2"5;
"A"
$PN"1"39;
%"Q_CAP"
"1","(-7000,625)","0","pure_quanta","I311";
;
LOCATION"C234"
$SEC"1"
CDS_SEC"1"
MATERIAL"EMPTY"
TOLERANCE"10%"
VALUE"0.001UF"
VOLTAGE"50V"
PACK_TYPE"C0402"
CDS_LIB"pure_quanta"
PART_NUMBER"CH30106KB19";
"B"
$PN"2"6;
"A"
$PN"1"40;
%"GND"
"1","(-6725,325)","0","pure_quanta_power","I312";
;
SIZE"1B"
CDS_LIB"pure_quanta_power"
HDL_POWER"GND";
"A<SIZE-1..0>\NAC"5;
%"GND"
"1","(-7000,325)","0","pure_quanta_power","I313";
;
CDS_LIB"pure_quanta_power"
SIZE"1B"
HDL_POWER"GND";
"A<SIZE-1..0>\NAC"6;
%"Q_RES"
"2","(-7300,1325)","0","pure_quanta","I314";
;
LOCATION"R526"
$SEC"1"
CDS_SEC"1"
WATTAGE"1/16W"
MATERIAL"CHIP"
TOLERANCE"5%"
VALUE"1K"
PACK_TYPE"0402LF"
CDS_LIB"pure_quanta"
PART_NUMBER"TMP_QCS21002JB34";
"A"
$PN"1"26;
"B"
$PN"2"36;
%"Q_CAP"
"1","(-7300,625)","0","pure_quanta","I315";
;
LOCATION"C233"
$SEC"1"
CDS_SEC"1"
MATERIAL"EMPTY"
TOLERANCE"10%"
VALUE"0.001UF"
VOLTAGE"50V"
PACK_TYPE"C0402"
CDS_LIB"pure_quanta"
PART_NUMBER"CH30106KB19";
"B"
$PN"2"7;
"A"
$PN"1"36;
%"Q_RES"
"2","(-7625,1325)","0","pure_quanta","I316";
;
LOCATION"R525"
$SEC"1"
CDS_SEC"1"
WATTAGE"1/16W"
MATERIAL"CHIP"
TOLERANCE"5%"
VALUE"1K"
PACK_TYPE"0402LF"
CDS_LIB"pure_quanta"
PART_NUMBER"TMP_QCS21002JB34";
"A"
$PN"1"26;
"B"
$PN"2"38;
%"Q_RES"
"2","(-7950,1325)","0","pure_quanta","I317";
;
LOCATION"R524"
$SEC"1"
CDS_SEC"1"
WATTAGE"1/16W"
MATERIAL"CHIP"
TOLERANCE"5%"
VALUE"1K"
PACK_TYPE"0402LF"
CDS_LIB"pure_quanta"
PART_NUMBER"TMP_QCS21002JB34";
"A"
$PN"1"26;
"B"
$PN"2"37;
%"Q_CAP"
"1","(-7625,625)","0","pure_quanta","I318";
;
LOCATION"C232"
$SEC"1"
CDS_SEC"1"
MATERIAL"EMPTY"
TOLERANCE"10%"
VALUE"0.001UF"
VOLTAGE"50V"
PACK_TYPE"C0402"
CDS_LIB"pure_quanta"
PART_NUMBER"CH30106KB19";
"B"
$PN"2"8;
"A"
$PN"1"38;
%"Q_CAP"
"1","(-7950,625)","0","pure_quanta","I319";
;
LOCATION"C231"
$SEC"1"
CDS_SEC"1"
MATERIAL"EMPTY"
TOLERANCE"10%"
VALUE"0.001UF"
VOLTAGE"50V"
PACK_TYPE"C0402"
CDS_LIB"pure_quanta"
PART_NUMBER"CH30106KB19";
"B"
$PN"2"9;
"A"
$PN"1"37;
%"GND"
"1","(-7300,325)","0","pure_quanta_power","I320";
;
SIZE"1B"
CDS_LIB"pure_quanta_power"
HDL_POWER"GND";
"A<SIZE-1..0>\NAC"7;
%"GND"
"1","(-7625,325)","0","pure_quanta_power","I321";
;
SIZE"1B"
CDS_LIB"pure_quanta_power"
HDL_POWER"GND";
"A<SIZE-1..0>\NAC"8;
%"GND"
"1","(-7950,325)","0","pure_quanta_power","I322";
;
CDS_LIB"pure_quanta_power"
SIZE"1B"
HDL_POWER"GND";
"A<SIZE-1..0>\NAC"9;
%"UNIVERSAL_POWER"
"1","(-8275,1600)","0","pure_quanta_power","I323";
;
HDL_POWER"PVDD18_S5_P1"
CDS_LIB"pure_quanta_power";
"A"26;
%"Q_RES"
"2","(-8275,1325)","0","pure_quanta","I324";
;
LOCATION"R523"
$SEC"1"
CDS_SEC"1"
WATTAGE"1/16W"
MATERIAL"CHIP"
TOLERANCE"5%"
VALUE"1K"
PACK_TYPE"0402LF"
CDS_LIB"pure_quanta"
PART_NUMBER"TMP_QCS21002JB34";
"A"
$PN"1"26;
"B"
$PN"2"24;
%"Q_CAP"
"1","(-8275,625)","0","pure_quanta","I325";
;
LOCATION"C230"
$SEC"1"
CDS_SEC"1"
MATERIAL"EMPTY"
TOLERANCE"10%"
VALUE"0.001UF"
VOLTAGE"50V"
PACK_TYPE"C0402"
CDS_LIB"pure_quanta"
PART_NUMBER"CH30106KB19";
"B"
$PN"2"10;
"A"
$PN"1"24;
%"GND"
"1","(-8275,325)","0","pure_quanta_power","I332";
;
CDS_LIB"pure_quanta_power"
SIZE"1B"
HDL_POWER"GND";
"A<SIZE-1..0>\NAC"10;
%"Q_RES"
"1","(-6775,5725)","0","pure_quanta","I333";
;
LOCATION"PR170"
$SEC"1"
CDS_SEC"1"
VALUE"0"
CDS_LIB"pure_quanta"
WATTAGE"1/16W"
MATERIAL"CHIP"
TOLERANCE"5%"
PART_NUMBER"CS00002JB38"
PACK_TYPE"0402LF";
"B"
$PN"2"74;
"A"
$PN"1"69;
%"Q_RES"
"1","(-6775,5775)","0","pure_quanta","I334";
;
LOCATION"PR169"
$SEC"1"
CDS_SEC"1"
VALUE"0"
CDS_LIB"pure_quanta"
WATTAGE"1/16W"
MATERIAL"CHIP"
TOLERANCE"5%"
PART_NUMBER"CS00002JB38"
PACK_TYPE"0402LF";
"B"
$PN"2"76;
"A"
$PN"1"70;
%"Q_RES"
"1","(-6775,5525)","0","pure_quanta","I337";
;
LOCATION"PR237"
$SEC"1"
CDS_SEC"1"
VALUE"0"
CDS_LIB"pure_quanta"
WATTAGE"1/16W"
MATERIAL"CHIP"
TOLERANCE"5%"
PART_NUMBER"CS00002JB38"
PACK_TYPE"0402LF";
"B"
$PN"2"75;
"A"
$PN"1"71;
%"Q_RES"
"1","(-6775,5575)","0","pure_quanta","I338";
;
LOCATION"PR236"
$SEC"1"
CDS_SEC"1"
VALUE"0"
CDS_LIB"pure_quanta"
WATTAGE"1/16W"
MATERIAL"CHIP"
TOLERANCE"5%"
PART_NUMBER"CS00002JB38"
PACK_TYPE"0402LF";
"B"
$PN"2"77;
"A"
$PN"1"72;
%"Q_RES"
"1","(-3100,4775)","0","pure_quanta","I361";
;
LOCATION"R618"
$SEC"1"
CDS_SEC"1"
VALUE"0"
CDS_LIB"pure_quanta"
WATTAGE"1/16W"
MATERIAL"CHIP"
TOLERANCE"5%"
PART_NUMBER"CS00002JB38"
PACK_TYPE"0402LF";
"B"
$PN"2"164;
"A"
$PN"1"147;
%"Q_RES"
"1","(-3100,4825)","0","pure_quanta","I362";
;
LOCATION"R486"
$SEC"1"
CDS_SEC"1"
VALUE"0"
CDS_LIB"pure_quanta"
WATTAGE"1/16W"
MATERIAL"CHIP"
TOLERANCE"5%"
PART_NUMBER"CS00002JB38"
PACK_TYPE"0402LF";
"B"
$PN"2"166;
"A"
$PN"1"146;
%"Q_RES"
"1","(-3100,4675)","0","pure_quanta","I363";
;
LOCATION"R928"
$SEC"1"
CDS_SEC"1"
VALUE"0"
CDS_LIB"pure_quanta"
WATTAGE"1/16W"
MATERIAL"CHIP"
TOLERANCE"5%"
PART_NUMBER"CS00002JB38"
PACK_TYPE"0402LF";
"B"
$PN"2"167;
"A"
$PN"1"149;
%"Q_RES"
"1","(-3100,4725)","0","pure_quanta","I364";
;
LOCATION"R862"
$SEC"1"
CDS_SEC"1"
VALUE"0"
CDS_LIB"pure_quanta"
WATTAGE"1/16W"
MATERIAL"CHIP"
TOLERANCE"5%"
PART_NUMBER"CS00002JB38"
PACK_TYPE"0402LF";
"B"
$PN"2"165;
"A"
$PN"1"148;
%"UNIVERSAL_GND"
"1","(-675,2300)","0","pure_quanta_power","I365";
;
CDS_LIB"pure_quanta_power"
HDL_POWER"GND";
"A"143;
%"UNIVERSAL_GND"
"1","(-150,3350)","0","pure_quanta_power","I370";
;
CDS_LIB"pure_quanta_power"
HDL_POWER"GND";
"A"144;
%"Q_RES"
"1","(-1425,3650)","0","pure_quanta","I371";
;
LOCATION"R929"
$SEC"1"
CDS_SEC"1"
VALUE"0"
CDS_LIB"pure_quanta"
WATTAGE"1/16W"
MATERIAL"CHIP"
TOLERANCE"5%"
PART_NUMBER"CS00002JB38"
PACK_TYPE"0402LF";
"B"
$PN"2"140;
"A"
$PN"1"135;
%"Q_RES"
"1","(-1425,3600)","0","pure_quanta","I372";
;
LOCATION"R930"
$SEC"1"
CDS_SEC"1"
VALUE"0"
CDS_LIB"pure_quanta"
WATTAGE"1/16W"
MATERIAL"CHIP"
TOLERANCE"5%"
PART_NUMBER"CS00002JB38"
PACK_TYPE"0402LF";
"B"
$PN"2"139;
"A"
$PN"1"136;
%"Q_RES"
"1","(-1425,3500)","0","pure_quanta","I373";
;
LOCATION"R932"
$SEC"1"
CDS_SEC"1"
VALUE"0"
CDS_LIB"pure_quanta"
WATTAGE"1/16W"
MATERIAL"CHIP"
TOLERANCE"5%"
PART_NUMBER"CS00002JB38"
PACK_TYPE"0402LF";
"B"
$PN"2"141;
"A"
$PN"1"138;
%"Q_RES"
"1","(-1425,3550)","0","pure_quanta","I374";
;
LOCATION"R931"
$SEC"1"
CDS_SEC"1"
VALUE"0"
CDS_LIB"pure_quanta"
WATTAGE"1/16W"
MATERIAL"CHIP"
TOLERANCE"5%"
PART_NUMBER"CS00002JB38"
PACK_TYPE"0402LF";
"B"
$PN"2"142;
"A"
$PN"1"137;
%"Q_RES"
"1","(-8750,3275)","0","pure_quanta","I387";
;
LOCATION"R517"
$SEC"1"
CDS_SEC"1"
VALUE"2.2K"
CDS_LIB"pure_quanta"
WATTAGE"1/16W"
MATERIAL"CHIP"
TOLERANCE"5%"
PART_NUMBER"CS22202JB07"
PACK_TYPE"0402LF";
"B"
$PN"2"30;
"A"
$PN"1"25;
%"Q_RES"
"1","(-8750,3325)","0","pure_quanta","I388";
;
LOCATION"R522"
$SEC"1"
CDS_SEC"1"
VALUE"2.2K"
CDS_LIB"pure_quanta"
WATTAGE"1/16W"
MATERIAL"CHIP"
TOLERANCE"5%"
PART_NUMBER"CS22202JB07"
PACK_TYPE"0402LF";
"B"
$PN"2"29;
"A"
$PN"1"25;
%"UNIVERSAL_POWER"
"1","(-9050,3600)","0","pure_quanta_power","I389";
;
HDL_POWER"P3V3_STBY"
CDS_LIB"pure_quanta_power";
"A"25;
%"Q_RES"
"1","(-8750,3175)","0","pure_quanta","I390";
;
LOCATION"R513"
$SEC"1"
CDS_SEC"1"
VALUE"2.2K"
CDS_LIB"pure_quanta"
WATTAGE"1/16W"
MATERIAL"CHIP"
TOLERANCE"5%"
PART_NUMBER"CS22202JB07"
PACK_TYPE"0402LF";
"B"
$PN"2"32;
"A"
$PN"1"25;
%"Q_RES"
"1","(-8750,3225)","0","pure_quanta","I391";
;
LOCATION"R515"
$SEC"1"
CDS_SEC"1"
VALUE"2.2K"
CDS_LIB"pure_quanta"
WATTAGE"1/16W"
MATERIAL"CHIP"
TOLERANCE"5%"
PART_NUMBER"CS22202JB07"
PACK_TYPE"0402LF";
"B"
$PN"2"31;
"A"
$PN"1"25;
%"Q_RES"
"1","(-500,5575)","0","pure_quanta","I396";
;
LOCATION"R520"
$SEC"1"
CDS_SEC"1"
VALUE"2.2K"
CDS_LIB"pure_quanta"
WATTAGE"1/16W"
MATERIAL"CHIP"
TOLERANCE"5%"
PART_NUMBER"CS22202JB07"
PACK_TYPE"0402LF";
"B"
$PN"2"18;
"A"
$PN"1"20;
%"Q_RES"
"1","(-500,5875)","0","pure_quanta","I398";
;
LOCATION"R535"
$SEC"1"
CDS_SEC"1"
VALUE"2.2K"
CDS_LIB"pure_quanta"
WATTAGE"1/16W"
MATERIAL"CHIP"
TOLERANCE"5%"
PART_NUMBER"CS22202JB07"
PACK_TYPE"0402LF";
"B"
$PN"2"18;
"A"
$PN"1"15;
%"Q_RES"
"1","(-500,5825)","0","pure_quanta","I399";
;
LOCATION"R536"
$SEC"1"
CDS_SEC"1"
VALUE"2.2K"
MATERIAL"EMPTY"
PACK_TYPE"0402LF"
PART_NUMBER"CS22202JB07"
TOLERANCE"5%"
WATTAGE"1/16W"
CDS_LIB"pure_quanta";
"B"
$PN"2"18;
"A"
$PN"1"13;
%"Q_RES"
"1","(-8750,3025)","0","pure_quanta","I400";
;
LOCATION"R512"
$SEC"1"
CDS_SEC"1"
VALUE"2.2K"
CDS_LIB"pure_quanta"
WATTAGE"1/16W"
MATERIAL"CHIP"
TOLERANCE"5%"
PART_NUMBER"CS22202JB07"
PACK_TYPE"0402LF";
"B"
$PN"2"35;
"A"
$PN"1"25;
%"Q_RES"
"1","(-8750,3075)","0","pure_quanta","I401";
;
LOCATION"R514"
$SEC"1"
CDS_SEC"1"
VALUE"2.2K"
CDS_LIB"pure_quanta"
WATTAGE"1/16W"
MATERIAL"CHIP"
TOLERANCE"5%"
PART_NUMBER"CS22202JB07"
PACK_TYPE"0402LF";
"B"
$PN"2"34;
"A"
$PN"1"25;
%"Q_RES"
"1","(-8750,3125)","0","pure_quanta","I402";
;
LOCATION"R516"
$SEC"1"
CDS_SEC"1"
VALUE"2.2K"
CDS_LIB"pure_quanta"
WATTAGE"1/16W"
MATERIAL"CHIP"
TOLERANCE"5%"
PART_NUMBER"CS22202JB07"
PACK_TYPE"0402LF";
"B"
$PN"2"33;
"A"
$PN"1"25;
%"Q_RES"
"2","(-8750,4825)","2","pure_quanta","I403";
;
LOCATION"R518"
$SEC"1"
CDS_SEC"1"
MATERIAL"CHIP"
VALUE"2.2K"
PACK_TYPE"0402LF"
CDS_LIB"pure_quanta"
WATTAGE"1/16W"
TOLERANCE"5%"
PART_NUMBER"CS22202JB07";
"A"
$PN"1"2;
"B"
$PN"2"27;
%"Q_RES"
"2","(-8750,4475)","2","pure_quanta","I404";
;
LOCATION"R519"
$SEC"1"
CDS_SEC"1"
MATERIAL"EMPTY"
VALUE"2.2K"
PACK_TYPE"0402LF"
CDS_LIB"pure_quanta"
WATTAGE"1/16W"
TOLERANCE"5%"
PART_NUMBER"CS22202JB07";
"A"
$PN"1"27;
"B"
$PN"2"4;
%"Q_RES"
"2","(-8625,4475)","0","pure_quanta","I405";
;
LOCATION"R521"
$SEC"1"
CDS_SEC"1"
MATERIAL"CHIP"
VALUE"2.2K"
PACK_TYPE"0402LF"
CDS_LIB"pure_quanta"
WATTAGE"1/16W"
TOLERANCE"5%"
PART_NUMBER"CS22202JB07";
"A"
$PN"1"28;
"B"
$PN"2"3;
%"Q_RES"
"1","(-500,6075)","0","pure_quanta","I406";
;
LOCATION"R531"
$SEC"1"
CDS_SEC"1"
VALUE"2.2K"
CDS_LIB"pure_quanta"
WATTAGE"1/16W"
MATERIAL"CHIP"
TOLERANCE"5%"
PART_NUMBER"CS22202JB07"
PACK_TYPE"0402LF";
"B"
$PN"2"18;
"A"
$PN"1"17;
%"Q_RES"
"1","(-500,6025)","0","pure_quanta","I407";
;
LOCATION"R532"
$SEC"1"
CDS_SEC"1"
VALUE"2.2K"
CDS_LIB"pure_quanta"
WATTAGE"1/16W"
MATERIAL"CHIP"
TOLERANCE"5%"
PART_NUMBER"CS22202JB07"
PACK_TYPE"0402LF";
"B"
$PN"2"18;
"A"
$PN"1"16;
%"Q_RES"
"1","(-500,5975)","0","pure_quanta","I408";
;
LOCATION"R533"
$SEC"1"
CDS_SEC"1"
VALUE"2.2K"
CDS_LIB"pure_quanta"
WATTAGE"1/16W"
MATERIAL"CHIP"
TOLERANCE"5%"
PART_NUMBER"CS22202JB07"
PACK_TYPE"0402LF";
"B"
$PN"2"18;
"A"
$PN"1"14;
%"Q_RES"
"1","(-500,5925)","0","pure_quanta","I409";
;
LOCATION"R534"
$SEC"1"
CDS_SEC"1"
VALUE"2.2K"
CDS_LIB"pure_quanta"
WATTAGE"1/16W"
MATERIAL"CHIP"
TOLERANCE"5%"
PART_NUMBER"CS22202JB07"
PACK_TYPE"0402LF";
"B"
$PN"2"18;
"A"
$PN"1"170;
%"Q_RES"
"1","(-500,5775)","0","pure_quanta","I410";
;
LOCATION"R537"
$SEC"1"
CDS_SEC"1"
VALUE"2.2K"
CDS_LIB"pure_quanta"
WATTAGE"1/16W"
MATERIAL"CHIP"
TOLERANCE"5%"
PART_NUMBER"CS22202JB07"
PACK_TYPE"0402LF";
"B"
$PN"2"18;
"A"
$PN"1"22;
%"Q_RES"
"1","(-500,5725)","0","pure_quanta","I411";
;
LOCATION"R538"
$SEC"1"
CDS_SEC"1"
VALUE"2.2K"
CDS_LIB"pure_quanta"
WATTAGE"1/16W"
MATERIAL"CHIP"
TOLERANCE"5%"
PART_NUMBER"CS22202JB07"
PACK_TYPE"0402LF";
"B"
$PN"2"18;
"A"
$PN"1"23;
%"Q_RES"
"1","(-500,5675)","0","pure_quanta","I412";
;
LOCATION"R539"
$SEC"1"
CDS_SEC"1"
VALUE"2.2K"
CDS_LIB"pure_quanta"
WATTAGE"1/16W"
MATERIAL"CHIP"
TOLERANCE"5%"
PART_NUMBER"CS22202JB07"
PACK_TYPE"0402LF";
"B"
$PN"2"18;
"A"
$PN"1"21;
%"Q_RES"
"1","(-500,5625)","0","pure_quanta","I413";
;
LOCATION"R540"
$SEC"1"
CDS_SEC"1"
VALUE"2.2K"
CDS_LIB"pure_quanta"
WATTAGE"1/16W"
MATERIAL"CHIP"
TOLERANCE"5%"
PART_NUMBER"CS22202JB07"
PACK_TYPE"0402LF";
"B"
$PN"2"18;
"A"
$PN"1"19;
%"Q_RES"
"1","(-3100,4975)","0","pure_quanta","I415";
;
LOCATION"R488"
$SEC"1"
CDS_SEC"1"
VALUE"33"
BOM_COST"MEM"
CDS_LIB"pure_quanta"
WATTAGE"1/16W"
MATERIAL"CHIP"
TOLERANCE"5%"
PART_NUMBER"CS03302JB29"
PACK_TYPE"0402LF"
ROOM"RST_CPU0_PLD_TO_DIMM";
"B"
$PN"2"168;
"A"
$PN"1"145;
%"Q_RES"
"1","(-3100,5125)","0","pure_quanta","I417";
;
LOCATION"R497"
$SEC"1"
CDS_SEC"1"
VALUE"33"
BOM_COST"MEM"
CDS_LIB"pure_quanta"
WATTAGE"1/16W"
MATERIAL"CHIP"
TOLERANCE"5%"
PART_NUMBER"CS03302JB29"
PACK_TYPE"0402LF"
ROOM"RST_CPU0_PLD_TO_DIMM";
"B"
$PN"2"169;
"A"
$PN"1"155;
END.
